# BASEBOARD_FAB2 (Tioga Pass) — schematic netlist excerpt (pin names and nets, part order shuffled) for the footprints in the layout excerpt that follows; sources: Cadence DE-HDL packaged netlist, KiCad conversion of Wiwynn_Tioga_Pass_MB.brd

C6B4  CAP  0.22UF 16V 10% X7R  pkg 0402  page 105 : A = P3E_CPU0_PE1_PCH_TXN<15> ; B = P3E_CPU0_PE1_PCH_C_TXN<15>
R1D9  RES  150.0 1% CHIP  pkg 0402  page 206 : A = SVID_CLK0_CPU1_R ; B = SVID_VCLK_PVCCIN_CPU1
C3D13  CAP_A  22.0UF 4V 20% X6S  pkg 0603V  page 76 : A = PVCCMCP_CPU1 ; B = GND

(kicad_pcb
	(version 20260206)
	(generator "pcbnew")
	(generator_version "10.0")
	(general
		(thickness 1.6)
		(legacy_teardrops no)
	)
	(paper "A4")
	(title_block
		(title "Wiwynn_Tioga_Pass_MB.brd")
		(comment 1 "Tioga Pass / footprints 409-411 of 4770")
	)
	(layers
		(0 "F.Cu" signal "TOP")
		(4 "In1.Cu" signal "L2GND")
		(6 "In2.Cu" signal "L3")
		(8 "In3.Cu" signal "L4GND")
		(10 "In4.Cu" signal "L5")
		(12 "In5.Cu" signal "L6GND")
		(14 "In6.Cu" signal "L7VCC")
		(16 "In7.Cu" signal "L8VCC")
		(18 "In8.Cu" signal "L9GND")
		(20 "In9.Cu" signal "L10")
		(22 "In10.Cu" signal "L11GND")
		(24 "In11.Cu" signal "L12")
		(26 "In12.Cu" signal "L13GND")
		(2 "B.Cu" signal "BOTTOM")
		(9 "F.Adhes" user "F.Adhesive")
		(11 "B.Adhes" user "B.Adhesive")
		(13 "F.Paste" user "Package Geometry/Pastemask Top")
		(15 "B.Paste" user "Package Geometry/Pastemask Bottom")
		(5 "F.SilkS" user "Ref Des/Silkscreen Top")
		(7 "B.SilkS" user "Ref Des/Silkscreen Bottom")
		(1 "F.Mask" user "Board Geometry/Soldermask Top")
		(3 "B.Mask" user "Board Geometry/Soldermask Bottom")
		(17 "Dwgs.User" user "User.Drawings")
		(19 "Cmts.User" user "User.Comments")
		(21 "Eco1.User" user "User.Eco1")
		(23 "Eco2.User" user "User.Eco2")
		(25 "Edge.Cuts" user "Board Geometry/Outline")
		(27 "Margin" user)
		(31 "F.CrtYd" user "Package Geometry/Place Bound Top")
		(29 "B.CrtYd" user "Package Geometry/Place Bound Bottom")
		(35 "F.Fab" user "Ref Des/Assembly Top")
		(33 "B.Fab" user "Ref Des/Assembly Bottom")
	)
	(footprint ""
		(layer "F.Cu")
		(at 110.908592 -77.429614)
		(property "Reference" "C3D13"
			(at 0 0 0)
			(layer "F.SilkS")
			(hide yes)
			(effects
				(font
					(size 1.27 1.27)
				)
			)
		)
		(property "Value" ""
			(at 0 0 0)
			(layer "F.Fab")
			(effects
				(font
					(size 1.27 1.27)
				)
			)
		)
		(duplicate_pad_numbers_are_jumpers no)
		(fp_poly
			(pts
				(xy -0.4953 -0.2032) (xy 0.4953 -0.2032) (xy 0.4953 1.6002) (xy -0.4953 1.6002)
			)
			(stroke
				(width 0)
				(type default)
			)
			(fill no)
			(layer "F.CrtYd")
		)
		(fp_line
			(start -0.4953 -0.2032)
			(end 0.4953 -0.2032)
			(stroke
				(width 0.1)
				(type default)
			)
			(layer "F.Fab")
		)
		(fp_line
			(start -0.4953 1.6002)
			(end -0.4953 -0.2032)
			(stroke
				(width 0.1)
				(type default)
			)
			(layer "F.Fab")
		)
		(fp_line
			(start 0.4953 -0.2032)
			(end 0.4953 1.6002)
			(stroke
				(width 0.1)
				(type default)
			)
			(layer "F.Fab")
		)
		(fp_line
			(start 0.4953 1.6002)
			(end -0.4953 1.6002)
			(stroke
				(width 0.1)
				(type default)
			)
			(layer "F.Fab")
		)
		(pad "1" smd rect
			(at 0 0)
			(size 0.762 0.889)
			(layers "F.Cu" "F.Mask" "F.Paste")
			(net "PVCCMCP_CPU1")
		)
		(pad "2" smd rect
			(at 0 1.397)
			(size 0.762 0.889)
			(layers "F.Cu" "F.Mask" "F.Paste")
			(net "GND")
		)
		(zone
			(layer "F.Cu")
			(hatch none 0.5)
			(connect_pads
				(clearance 0)
			)
			(min_thickness 0.25)
			(keepout
				(tracks not_allowed)
				(vias allowed)
				(pads allowed)
				(copperpour not_allowed)
				(footprints allowed)
			)
			(placement
				(enabled no)
				(sheetname "")
			)
			(fill
				(thermal_gap 0.5)
				(thermal_bridge_width 0.5)
				(island_removal_mode 0)
			)
			(polygon
				(pts
					(xy 110.527592 -76.985114) (xy 111.289592 -76.985114) (xy 111.289592 -76.477114) (xy 110.527592 -76.477114)
				)
			)
		)
	)
	(footprint ""
		(layer "F.Cu")
		(at 320.6115 -124.587 90)
		(property "Reference" "C6B4"
			(at -0.8382 -0.67818 90)
			(unlocked yes)
			(layer "F.SilkS")
			(effects
				(font
					(size 0.4064 0.254)
					(thickness 0.1524)
				)
				(justify left)
			)
		)
		(property "Value" ""
			(at 0 0 90)
			(layer "F.Fab")
			(effects
				(font
					(size 1.27 1.27)
				)
			)
		)
		(duplicate_pad_numbers_are_jumpers no)
		(fp_poly
			(pts
				(xy 0.3048 -0.1016) (xy 0.3048 0.9906) (xy -0.3048 0.9906) (xy -0.3048 -0.1016)
			)
			(stroke
				(width 0)
				(type default)
			)
			(fill no)
			(layer "F.CrtYd")
		)
		(fp_line
			(start 0.3048 -0.1016)
			(end -0.3048 -0.1016)
			(stroke
				(width 0.1)
				(type default)
			)
			(layer "F.Fab")
		)
		(fp_line
			(start -0.3048 -0.1016)
			(end -0.3048 0.9906)
			(stroke
				(width 0.1)
				(type default)
			)
			(layer "F.Fab")
		)
		(fp_line
			(start 0.3048 0.9906)
			(end 0.3048 -0.1016)
			(stroke
				(width 0.1)
				(type default)
			)
			(layer "F.Fab")
		)
		(fp_line
			(start -0.3048 0.9906)
			(end 0.3048 0.9906)
			(stroke
				(width 0.1)
				(type default)
			)
			(layer "F.Fab")
		)
		(pad "1" smd rect
			(at 0 0 90)
			(size 0.508 0.508)
			(layers "F.Cu" "F.Mask" "F.Paste")
			(net "P3E_CPU0_PE1_PCH_TXN<15>")
		)
		(pad "2" smd rect
			(at 0 0.889 90)
			(size 0.508 0.508)
			(layers "F.Cu" "F.Mask" "F.Paste")
			(net "P3E_CPU0_PE1_PCH_C_TXN<15>")
		)
		(zone
			(layer "F.Cu")
			(hatch none 0.5)
			(connect_pads
				(clearance 0)
			)
			(min_thickness 0.25)
			(keepout
				(tracks allowed)
				(vias not_allowed)
				(pads allowed)
				(copperpour not_allowed)
				(footprints allowed)
			)
			(placement
				(enabled no)
				(sheetname "")
			)
			(fill
				(thermal_gap 0.5)
				(thermal_bridge_width 0.5)
				(island_removal_mode 0)
			)
			(polygon
				(pts
					(xy 320.8655 -124.333) (xy 320.8655 -124.841) (xy 321.2465 -124.841) (xy 321.2465 -124.333)
				)
			)
		)
		(zone
			(layer "F.Cu")
			(hatch none 0.5)
			(connect_pads
				(clearance 0)
			)
			(min_thickness 0.25)
			(keepout
				(tracks not_allowed)
				(vias allowed)
				(pads allowed)
				(copperpour not_allowed)
				(footprints allowed)
			)
			(placement
				(enabled no)
				(sheetname "")
			)
			(fill
				(thermal_gap 0.5)
				(thermal_bridge_width 0.5)
				(island_removal_mode 0)
			)
			(polygon
				(pts
					(xy 321.2465 -124.333) (xy 321.2465 -124.841) (xy 320.8655 -124.841) (xy 320.8655 -124.333)
				)
			)
		)
	)
	(footprint ""
		(layer "F.Cu")
		(at 17.526 -86.8172 180)
		(property "Reference" "R1D9"
			(at 0 0 180)
			(layer "F.SilkS")
			(hide yes)
			(effects
				(font
					(size 1.27 1.27)
				)
			)
		)
		(property "Value" ""
			(at 0 0 180)
			(layer "F.Fab")
			(effects
				(font
					(size 1.27 1.27)
				)
			)
		)
		(duplicate_pad_numbers_are_jumpers no)
		(fp_rect
			(start 0.2794 -0.1016)
			(end -0.2794 0.9906)
			(stroke
				(width 0)
				(type default)
			)
			(fill no)
			(layer "F.CrtYd")
		)
		(fp_line
			(start 0.2794 0.9906)
			(end 0.2794 -0.1016)
			(stroke
				(width 0.1)
				(type default)
			)
			(layer "F.Fab")
		)
		(fp_line
			(start 0.2794 -0.1016)
			(end -0.2794 -0.1016)
			(stroke
				(width 0.1)
				(type default)
			)
			(layer "F.Fab")
		)
		(fp_line
			(start -0.2794 0.9906)
			(end 0.2794 0.9906)
			(stroke
				(width 0.1)
				(type default)
			)
			(layer "F.Fab")
		)
		(fp_line
			(start -0.2794 -0.1016)
			(end -0.2794 0.9906)
			(stroke
				(width 0.1)
				(type default)
			)
			(layer "F.Fab")
		)
		(pad "1" smd rect
			(at 0 0 180)
			(size 0.508 0.508)
			(layers "F.Cu" "F.Mask" "F.Paste")
			(net "SVID_CLK0_CPU1_R")
		)
		(pad "2" smd rect
			(at 0 0.889 180)
			(size 0.508 0.508)
			(layers "F.Cu" "F.Mask" "F.Paste")
			(net "SVID_VCLK_PVCCIN_CPU1")
		)
		(zone
			(layer "F.Cu")
			(hatch none 0.5)
			(connect_pads
				(clearance 0)
			)
			(min_thickness 0.25)
			(keepout
				(tracks not_allowed)
				(vias allowed)
				(pads allowed)
				(copperpour not_allowed)
				(footprints allowed)
			)
			(placement
				(enabled no)
				(sheetname "")
			)
			(fill
				(thermal_gap 0.5)
				(thermal_bridge_width 0.5)
				(island_removal_mode 0)
			)
			(polygon
				(pts
					(xy 17.272 -87.0712) (xy 17.78 -87.0712) (xy 17.78 -87.4522) (xy 17.272 -87.4522)
				)
			)
		)
		(zone
			(layer "F.Cu")
			(hatch none 0.5)
			(connect_pads
				(clearance 0)
			)
			(min_thickness 0.25)
			(keepout
				(tracks allowed)
				(vias not_allowed)
				(pads allowed)
				(copperpour not_allowed)
				(footprints allowed)
			)
			(placement
				(enabled no)
				(sheetname "")
			)
			(fill
				(thermal_gap 0.5)
				(thermal_bridge_width 0.5)
				(island_removal_mode 0)
			)
			(polygon
				(pts
					(xy 17.272 -87.0712) (xy 17.78 -87.0712) (xy 17.78 -87.4522) (xy 17.272 -87.4522)
				)
			)
		)
	)
)
